(kicad_pcb
	(version 20260206)
	(generator "pcbnew")
	(generator_version "10.0")
	(general
		(thickness 1.6)
		(legacy_teardrops no)
	)
	(paper "A4")
	(title_block
		(title "04192023_DAF0TMB3IC0_F0TG_MB_C_brd_V02_OCP.brd")
		(comment 1 "Grand Teton / footprints 2738-2744 of 8354")
	)
	(layers
		(0 "F.Cu" signal "TOP")
		(4 "In1.Cu" signal "GND")
		(6 "In2.Cu" signal "IN1")
		(8 "In3.Cu" signal "GND1")
		(10 "In4.Cu" signal "IN2")
		(12 "In5.Cu" signal "GND2")
		(14 "In6.Cu" signal "IN3")
		(16 "In7.Cu" signal "GND3")
		(18 "In8.Cu" signal "VCC")
		(20 "In9.Cu" signal "VCC1")
		(22 "In10.Cu" signal "GND4")
		(24 "In11.Cu" signal "IN4")
		(26 "In12.Cu" signal "GND5")
		(28 "In13.Cu" signal "IN5")
		(30 "In14.Cu" signal "GND6")
		(32 "In15.Cu" signal "IN6")
		(34 "In16.Cu" signal "GND7")
		(2 "B.Cu" signal "BOTTOM")
		(9 "F.Adhes" user "F.Adhesive")
		(11 "B.Adhes" user "B.Adhesive")
		(13 "F.Paste" user "Package Geometry/Pastemask Top")
		(15 "B.Paste" user "Package Geometry/Pastemask Bottom")
		(5 "F.SilkS" user "Ref Des/Silkscreen Top")
		(7 "B.SilkS" user "Ref Des/Silkscreen Bottom")
		(1 "F.Mask" user "Board Geometry/Soldermask Top")
		(3 "B.Mask" user "Board Geometry/Soldermask Bottom")
		(17 "Dwgs.User" user "User.Drawings")
		(19 "Cmts.User" user "User.Comments")
		(21 "Eco1.User" user "User.Eco1")
		(23 "Eco2.User" user "User.Eco2")
		(25 "Edge.Cuts" user "Board Geometry/Outline")
		(27 "Margin" user)
		(31 "F.CrtYd" user "Package Geometry/Place Bound Top")
		(29 "B.CrtYd" user "Package Geometry/Place Bound Bottom")
		(35 "F.Fab" user "Ref Des/Assembly Top")
		(33 "B.Fab" user "Ref Des/Assembly Bottom")
	)
	(footprint ""
		(layer "F.Cu")
		(at 226.0981 -407.068782 180)
		(property "Reference" "PR3982"
			(at 0 0 180)
			(layer "F.SilkS")
			(hide yes)
			(effects
				(font
					(size 1.27 1.27)
				)
			)
		)
		(property "Value" ""
			(at 0 0 180)
			(layer "F.Fab")
			(effects
				(font
					(size 1.27 1.27)
				)
			)
		)
		(duplicate_pad_numbers_are_jumpers no)
		(fp_line
			(start 0.7874 0.4064)
			(end -0.7874 0.4064)
			(stroke
				(width 0.1524)
				(type default)
			)
			(layer "F.SilkS")
		)
		(fp_line
			(start 0.7874 -0.4064)
			(end 0.7874 0.4064)
			(stroke
				(width 0.1524)
				(type default)
			)
			(layer "F.SilkS")
		)
		(fp_line
			(start -0.7874 0.4064)
			(end -0.7874 -0.4064)
			(stroke
				(width 0.1524)
				(type default)
			)
			(layer "F.SilkS")
		)
		(fp_line
			(start -0.7874 -0.4064)
			(end 0.7874 -0.4064)
			(stroke
				(width 0.1524)
				(type default)
			)
			(layer "F.SilkS")
		)
		(fp_line
			(start 0.67945 0.3048)
			(end 0.120396 0.3048)
			(stroke
				(width 0.1)
				(type default)
			)
			(layer "F.Fab")
		)
		(fp_line
			(start 0.67945 -0.3048)
			(end 0.67945 0.3048)
			(stroke
				(width 0.1)
				(type default)
			)
			(layer "F.Fab")
		)
		(fp_line
			(start 0.12065 -0.2794)
			(end 0.12065 -0.3048)
			(stroke
				(width 0.1)
				(type default)
			)
			(layer "F.Fab")
		)
		(fp_line
			(start 0.12065 -0.3048)
			(end 0.67945 -0.3048)
			(stroke
				(width 0.1)
				(type default)
			)
			(layer "F.Fab")
		)
		(fp_line
			(start 0.120396 0.3048)
			(end 0.120396 0.2794)
			(stroke
				(width 0.1)
				(type default)
			)
			(layer "F.Fab")
		)
		(fp_line
			(start 0.120396 0.2794)
			(end -0.12065 0.2794)
			(stroke
				(width 0.1)
				(type default)
			)
			(layer "F.Fab")
		)
		(fp_line
			(start -0.12065 0.3048)
			(end -0.67945 0.3048)
			(stroke
				(width 0.1)
				(type default)
			)
			(layer "F.Fab")
		)
		(fp_line
			(start -0.12065 0.2794)
			(end -0.12065 0.3048)
			(stroke
				(width 0.1)
				(type default)
			)
			(layer "F.Fab")
		)
		(fp_line
			(start -0.12065 -0.2794)
			(end 0.12065 -0.2794)
			(stroke
				(width 0.1)
				(type default)
			)
			(layer "F.Fab")
		)
		(fp_line
			(start -0.12065 -0.305054)
			(end -0.12065 -0.2794)
			(stroke
				(width 0.1)
				(type default)
			)
			(layer "F.Fab")
		)
		(fp_line
			(start -0.67945 0.3048)
			(end -0.67945 -0.305054)
			(stroke
				(width 0.1)
				(type default)
			)
			(layer "F.Fab")
		)
		(fp_line
			(start -0.67945 -0.305054)
			(end -0.12065 -0.305054)
			(stroke
				(width 0.1)
				(type default)
			)
			(layer "F.Fab")
		)
		(pad "1" smd circle
			(at -0.40005 0 180)
			(size 0 0)
			(layers "F.Cu" "F.Mask" "F.Paste")
			(net "AGND_HSC")
		)
		(pad "2" smd circle
			(at 0.40005 0 180)
			(size 0 0)
			(layers "F.Cu" "F.Mask" "F.Paste")
			(net "HSC_MODE_3")
		)
	)
	(footprint ""
		(layer "F.Cu")
		(at 137.974832 -76.242672 90)
		(property "Reference" "PL6002"
			(at 0 0 90)
			(layer "F.SilkS")
			(hide yes)
			(effects
				(font
					(size 1.27 1.27)
				)
			)
		)
		(property "Value" ""
			(at 0 0 90)
			(layer "F.Fab")
			(effects
				(font
					(size 1.27 1.27)
				)
			)
		)
		(duplicate_pad_numbers_are_jumpers no)
		(fp_line
			(start -1.27 -0.5842)
			(end 1.27 -0.5842)
			(stroke
				(width 0.1524)
				(type default)
			)
			(layer "F.SilkS")
		)
		(fp_line
			(start -1.27 -0.5588)
			(end -1.27 -0.5842)
			(stroke
				(width 0.1524)
				(type default)
			)
			(layer "F.SilkS")
		)
		(fp_line
			(start 1.27 0.5842)
			(end 1.27 -0.5842)
			(stroke
				(width 0.1524)
				(type default)
			)
			(layer "F.SilkS")
		)
		(fp_line
			(start 1.27 0.5842)
			(end -1.27 0.5842)
			(stroke
				(width 0.1524)
				(type default)
			)
			(layer "F.SilkS")
		)
		(fp_line
			(start -1.27 0.5842)
			(end -1.27 -0.5842)
			(stroke
				(width 0.1524)
				(type default)
			)
			(layer "F.SilkS")
		)
		(fp_line
			(start 0.9144 -0.508)
			(end 0.9144 -0.406654)
			(stroke
				(width 0.1)
				(type default)
			)
			(layer "F.Fab")
		)
		(fp_line
			(start -0.9144 -0.508)
			(end 0.9144 -0.508)
			(stroke
				(width 0.1)
				(type default)
			)
			(layer "F.Fab")
		)
		(fp_line
			(start 1.1938 -0.406654)
			(end 1.1938 0.4064)
			(stroke
				(width 0.1)
				(type default)
			)
			(layer "F.Fab")
		)
		(fp_line
			(start 0.9144 -0.406654)
			(end 1.1938 -0.406654)
			(stroke
				(width 0.1)
				(type default)
			)
			(layer "F.Fab")
		)
		(fp_line
			(start -0.9144 -0.406654)
			(end -0.9144 -0.508)
			(stroke
				(width 0.1)
				(type default)
			)
			(layer "F.Fab")
		)
		(fp_line
			(start -1.194308 -0.406654)
			(end -0.9144 -0.406654)
			(stroke
				(width 0.1)
				(type default)
			)
			(layer "F.Fab")
		)
		(fp_line
			(start 1.1938 0.4064)
			(end 0.9144 0.4064)
			(stroke
				(width 0.1)
				(type default)
			)
			(layer "F.Fab")
		)
		(fp_line
			(start 0.9144 0.4064)
			(end 0.9144 0.508)
			(stroke
				(width 0.1)
				(type default)
			)
			(layer "F.Fab")
		)
		(fp_line
			(start -0.9144 0.406654)
			(end -1.194308 0.406654)
			(stroke
				(width 0.1)
				(type default)
			)
			(layer "F.Fab")
		)
		(fp_line
			(start -1.194308 0.406654)
			(end -1.194308 -0.406654)
			(stroke
				(width 0.1)
				(type default)
			)
			(layer "F.Fab")
		)
		(fp_line
			(start 0.9144 0.508)
			(end -0.9144 0.508)
			(stroke
				(width 0.1)
				(type default)
			)
			(layer "F.Fab")
		)
		(fp_line
			(start -0.9144 0.508)
			(end -0.9144 0.406654)
			(stroke
				(width 0.1)
				(type default)
			)
			(layer "F.Fab")
		)
		(pad "1" smd rect
			(at -0.7366 0)
			(size 0.7112 0.8128)
			(layers "F.Cu" "F.Mask" "F.Paste")
			(net "P12V_AUX")
		)
		(pad "2" smd rect
			(at 0.7366 0)
			(size 0.7112 0.8128)
			(layers "F.Cu" "F.Mask" "F.Paste")
			(net "SW_P12V_AUX_P1V8_AUX_FLT")
		)
	)
	(footprint ""
		(layer "F.Cu")
		(at 120.358662 -16.50365)
		(property "Reference" "R4201"
			(at 0 0 0)
			(layer "F.SilkS")
			(hide yes)
			(effects
				(font
					(size 1.27 1.27)
				)
			)
		)
		(property "Value" ""
			(at 0 0 0)
			(layer "F.Fab")
			(effects
				(font
					(size 1.27 1.27)
				)
			)
		)
		(duplicate_pad_numbers_are_jumpers no)
		(fp_line
			(start -0.7874 -0.4064)
			(end 0.7874 -0.4064)
			(stroke
				(width 0.1524)
				(type default)
			)
			(layer "F.SilkS")
		)
		(fp_line
			(start -0.7874 0.4064)
			(end -0.7874 -0.4064)
			(stroke
				(width 0.1524)
				(type default)
			)
			(layer "F.SilkS")
		)
		(fp_line
			(start 0.7874 -0.4064)
			(end 0.7874 0.4064)
			(stroke
				(width 0.1524)
				(type default)
			)
			(layer "F.SilkS")
		)
		(fp_line
			(start 0.7874 0.4064)
			(end -0.7874 0.4064)
			(stroke
				(width 0.1524)
				(type default)
			)
			(layer "F.SilkS")
		)
		(fp_line
			(start -0.67945 -0.305054)
			(end -0.12065 -0.305054)
			(stroke
				(width 0.1)
				(type default)
			)
			(layer "F.Fab")
		)
		(fp_line
			(start -0.67945 0.3048)
			(end -0.67945 -0.305054)
			(stroke
				(width 0.1)
				(type default)
			)
			(layer "F.Fab")
		)
		(fp_line
			(start -0.12065 -0.305054)
			(end -0.12065 -0.2794)
			(stroke
				(width 0.1)
				(type default)
			)
			(layer "F.Fab")
		)
		(fp_line
			(start -0.12065 -0.2794)
			(end 0.12065 -0.2794)
			(stroke
				(width 0.1)
				(type default)
			)
			(layer "F.Fab")
		)
		(fp_line
			(start -0.12065 0.2794)
			(end -0.12065 0.3048)
			(stroke
				(width 0.1)
				(type default)
			)
			(layer "F.Fab")
		)
		(fp_line
			(start -0.12065 0.3048)
			(end -0.67945 0.3048)
			(stroke
				(width 0.1)
				(type default)
			)
			(layer "F.Fab")
		)
		(fp_line
			(start 0.120396 0.2794)
			(end -0.12065 0.2794)
			(stroke
				(width 0.1)
				(type default)
			)
			(layer "F.Fab")
		)
		(fp_line
			(start 0.120396 0.3048)
			(end 0.120396 0.2794)
			(stroke
				(width 0.1)
				(type default)
			)
			(layer "F.Fab")
		)
		(fp_line
			(start 0.12065 -0.3048)
			(end 0.67945 -0.3048)
			(stroke
				(width 0.1)
				(type default)
			)
			(layer "F.Fab")
		)
		(fp_line
			(start 0.12065 -0.2794)
			(end 0.12065 -0.3048)
			(stroke
				(width 0.1)
				(type default)
			)
			(layer "F.Fab")
		)
		(fp_line
			(start 0.67945 -0.3048)
			(end 0.67945 0.3048)
			(stroke
				(width 0.1)
				(type default)
			)
			(layer "F.Fab")
		)
		(fp_line
			(start 0.67945 0.3048)
			(end 0.120396 0.3048)
			(stroke
				(width 0.1)
				(type default)
			)
			(layer "F.Fab")
		)
		(pad "1" smd circle
			(at -0.40005 0)
			(size 0 0)
			(layers "F.Cu" "F.Mask" "F.Paste")
			(net "U273_3_ADD0")
		)
		(pad "2" smd circle
			(at 0.40005 0)
			(size 0 0)
			(layers "F.Cu" "F.Mask" "F.Paste")
			(net "GND")
		)
	)
	(footprint ""
		(layer "F.Cu")
		(at 314.567316 -113.60277)
		(property "Reference" "C1"
			(at 0 0 0)
			(layer "F.SilkS")
			(hide yes)
			(effects
				(font
					(size 1.27 1.27)
				)
			)
		)
		(property "Value" ""
			(at 0 0 0)
			(layer "F.Fab")
			(effects
				(font
					(size 1.27 1.27)
				)
			)
		)
		(duplicate_pad_numbers_are_jumpers no)
		(fp_line
			(start -0.7874 -0.4064)
			(end 0.7874 -0.4064)
			(stroke
				(width 0.1524)
				(type default)
			)
			(layer "F.SilkS")
		)
		(fp_line
			(start -0.7874 0.4064)
			(end -0.7874 -0.4064)
			(stroke
				(width 0.1524)
				(type default)
			)
			(layer "F.SilkS")
		)
		(fp_line
			(start 0.7874 -0.4064)
			(end 0.7874 0.4064)
			(stroke
				(width 0.1524)
				(type default)
			)
			(layer "F.SilkS")
		)
		(fp_line
			(start 0.7874 0.4064)
			(end -0.7874 0.4064)
			(stroke
				(width 0.1524)
				(type default)
			)
			(layer "F.SilkS")
		)
		(fp_line
			(start -0.67945 -0.305054)
			(end -0.12065 -0.305054)
			(stroke
				(width 0.1)
				(type default)
			)
			(layer "F.Fab")
		)
		(fp_line
			(start -0.67945 0.3048)
			(end -0.67945 -0.305054)
			(stroke
				(width 0.1)
				(type default)
			)
			(layer "F.Fab")
		)
		(fp_line
			(start -0.12065 -0.305054)
			(end -0.12065 -0.2794)
			(stroke
				(width 0.1)
				(type default)
			)
			(layer "F.Fab")
		)
		(fp_line
			(start -0.12065 -0.2794)
			(end 0.12065 -0.2794)
			(stroke
				(width 0.1)
				(type default)
			)
			(layer "F.Fab")
		)
		(fp_line
			(start -0.12065 0.2794)
			(end -0.12065 0.3048)
			(stroke
				(width 0.1)
				(type default)
			)
			(layer "F.Fab")
		)
		(fp_line
			(start -0.12065 0.3048)
			(end -0.67945 0.3048)
			(stroke
				(width 0.1)
				(type default)
			)
			(layer "F.Fab")
		)
		(fp_line
			(start 0.120396 0.2794)
			(end -0.12065 0.2794)
			(stroke
				(width 0.1)
				(type default)
			)
			(layer "F.Fab")
		)
		(fp_line
			(start 0.120396 0.3048)
			(end 0.120396 0.2794)
			(stroke
				(width 0.1)
				(type default)
			)
			(layer "F.Fab")
		)
		(fp_line
			(start 0.12065 -0.3048)
			(end 0.67945 -0.3048)
			(stroke
				(width 0.1)
				(type default)
			)
			(layer "F.Fab")
		)
		(fp_line
			(start 0.12065 -0.2794)
			(end 0.12065 -0.3048)
			(stroke
				(width 0.1)
				(type default)
			)
			(layer "F.Fab")
		)
		(fp_line
			(start 0.67945 -0.3048)
			(end 0.67945 0.3048)
			(stroke
				(width 0.1)
				(type default)
			)
			(layer "F.Fab")
		)
		(fp_line
			(start 0.67945 0.3048)
			(end 0.120396 0.3048)
			(stroke
				(width 0.1)
				(type default)
			)
			(layer "F.Fab")
		)
		(pad "1" smd circle
			(at -0.40005 0)
			(size 0 0)
			(layers "F.Cu" "F.Mask" "F.Paste")
			(net "P3V3_AUX")
		)
		(pad "2" smd circle
			(at 0.40005 0)
			(size 0 0)
			(layers "F.Cu" "F.Mask" "F.Paste")
			(net "GND")
		)
	)
	(footprint ""
		(layer "F.Cu")
		(at 69.741034 -376.067828)
		(property "Reference" "C809"
			(at 0 0 0)
			(layer "F.SilkS")
			(hide yes)
			(effects
				(font
					(size 1.27 1.27)
				)
			)
		)
		(property "Value" ""
			(at 0 0 0)
			(layer "F.Fab")
			(effects
				(font
					(size 1.27 1.27)
				)
			)
		)
		(duplicate_pad_numbers_are_jumpers no)
		(fp_line
			(start -0.299974 -0.150114)
			(end 0.299974 -0.150114)
			(stroke
				(width 0.1)
				(type default)
			)
			(layer "F.Fab")
		)
		(fp_line
			(start -0.299974 0.150114)
			(end -0.299974 -0.150114)
			(stroke
				(width 0.1)
				(type default)
			)
			(layer "F.Fab")
		)
		(fp_line
			(start 0.299974 -0.150114)
			(end 0.299974 0.150114)
			(stroke
				(width 0.1)
				(type default)
			)
			(layer "F.Fab")
		)
		(fp_line
			(start 0.299974 0.150114)
			(end -0.299974 0.150114)
			(stroke
				(width 0.1)
				(type default)
			)
			(layer "F.Fab")
		)
		(pad "1" smd rect
			(at -0.2667 0)
			(size 0.3048 0.381)
			(layers "F.Cu" "F.Mask" "F.Paste")
			(net "P5E_CPU1_P0_TX_C_DP<14>")
		)
		(pad "2" smd rect
			(at 0.2667 0)
			(size 0.3048 0.381)
			(layers "F.Cu" "F.Mask" "F.Paste")
			(net "P5E_CPU1_P0_TX_DP<14>")
		)
	)
	(footprint ""
		(layer "F.Cu")
		(at 317.709296 -383.88163 -90)
		(property "Reference" "C913"
			(at 0 0 270)
			(layer "F.SilkS")
			(hide yes)
			(effects
				(font
					(size 1.27 1.27)
				)
			)
		)
		(property "Value" ""
			(at 0 0 270)
			(layer "F.Fab")
			(effects
				(font
					(size 1.27 1.27)
				)
			)
		)
		(duplicate_pad_numbers_are_jumpers no)
		(fp_line
			(start -0.299974 0.150114)
			(end -0.299974 -0.150114)
			(stroke
				(width 0.1)
				(type default)
			)
			(layer "F.Fab")
		)
		(fp_line
			(start 0.299974 0.150114)
			(end -0.299974 0.150114)
			(stroke
				(width 0.1)
				(type default)
			)
			(layer "F.Fab")
		)
		(fp_line
			(start -0.299974 -0.150114)
			(end 0.299974 -0.150114)
			(stroke
				(width 0.1)
				(type default)
			)
			(layer "F.Fab")
		)
		(fp_line
			(start 0.299974 -0.150114)
			(end 0.299974 0.150114)
			(stroke
				(width 0.1)
				(type default)
			)
			(layer "F.Fab")
		)
		(pad "1" smd rect
			(at -0.2667 0 270)
			(size 0.3048 0.381)
			(layers "F.Cu" "F.Mask" "F.Paste")
			(net "P5E_CPU0_P0_TX_C_DP<10>")
		)
		(pad "2" smd rect
			(at 0.2667 0 270)
			(size 0.3048 0.381)
			(layers "F.Cu" "F.Mask" "F.Paste")
			(net "P5E_CPU0_P0_TX_DP<10>")
		)
	)
	(footprint ""
		(layer "F.Cu")
		(at 330.365354 -133.964172 180)
		(property "Reference" "PC6001"
			(at 0 0 180)
			(layer "F.SilkS")
			(hide yes)
			(effects
				(font
					(size 1.27 1.27)
				)
			)
		)
		(property "Value" ""
			(at 0 0 180)
			(layer "F.Fab")
			(effects
				(font
					(size 1.27 1.27)
				)
			)
		)
		(duplicate_pad_numbers_are_jumpers no)
		(fp_line
			(start 0.7874 0.4064)
			(end -0.7874 0.4064)
			(stroke
				(width 0.1524)
				(type default)
			)
			(layer "F.SilkS")
		)
		(fp_line
			(start 0.7874 -0.4064)
			(end 0.7874 0.4064)
			(stroke
				(width 0.1524)
				(type default)
			)
			(layer "F.SilkS")
		)
		(fp_line
			(start -0.7874 0.4064)
			(end -0.7874 -0.4064)
			(stroke
				(width 0.1524)
				(type default)
			)
			(layer "F.SilkS")
		)
		(fp_line
			(start -0.7874 -0.4064)
			(end 0.7874 -0.4064)
			(stroke
				(width 0.1524)
				(type default)
			)
			(layer "F.SilkS")
		)
		(fp_line
			(start 0.67945 0.3048)
			(end 0.120396 0.3048)
			(stroke
				(width 0.1)
				(type default)
			)
			(layer "F.Fab")
		)
		(fp_line
			(start 0.67945 -0.3048)
			(end 0.67945 0.3048)
			(stroke
				(width 0.1)
				(type default)
			)
			(layer "F.Fab")
		)
		(fp_line
			(start 0.12065 -0.2794)
			(end 0.12065 -0.3048)
			(stroke
				(width 0.1)
				(type default)
			)
			(layer "F.Fab")
		)
		(fp_line
			(start 0.12065 -0.3048)
			(end 0.67945 -0.3048)
			(stroke
				(width 0.1)
				(type default)
			)
			(layer "F.Fab")
		)
		(fp_line
			(start 0.120396 0.3048)
			(end 0.120396 0.2794)
			(stroke
				(width 0.1)
				(type default)
			)
			(layer "F.Fab")
		)
		(fp_line
			(start 0.120396 0.2794)
			(end -0.12065 0.2794)
			(stroke
				(width 0.1)
				(type default)
			)
			(layer "F.Fab")
		)
		(fp_line
			(start -0.12065 0.3048)
			(end -0.67945 0.3048)
			(stroke
				(width 0.1)
				(type default)
			)
			(layer "F.Fab")
		)
		(fp_line
			(start -0.12065 0.2794)
			(end -0.12065 0.3048)
			(stroke
				(width 0.1)
				(type default)
			)
			(layer "F.Fab")
		)
		(fp_line
			(start -0.12065 -0.2794)
			(end 0.12065 -0.2794)
			(stroke
				(width 0.1)
				(type default)
			)
			(layer "F.Fab")
		)
		(fp_line
			(start -0.12065 -0.305054)
			(end -0.12065 -0.2794)
			(stroke
				(width 0.1)
				(type default)
			)
			(layer "F.Fab")
		)
		(fp_line
			(start -0.67945 0.3048)
			(end -0.67945 -0.305054)
			(stroke
				(width 0.1)
				(type default)
			)
			(layer "F.Fab")
		)
		(fp_line
			(start -0.67945 -0.305054)
			(end -0.12065 -0.305054)
			(stroke
				(width 0.1)
				(type default)
			)
			(layer "F.Fab")
		)
		(pad "1" smd circle
			(at -0.40005 0 180)
			(size 0 0)
			(layers "F.Cu" "F.Mask" "F.Paste")
			(net "P12V_AUX")
		)
		(pad "2" smd circle
			(at 0.40005 0 180)
			(size 0 0)
			(layers "F.Cu" "F.Mask" "F.Paste")
			(net "GND")
		)
	)
)
